# T6G (Grand Teton) — schematic netlist excerpt (pin names and nets, part order shuffled) for the footprints in the layout excerpt that follows; sources: Cadence DE-HDL packaged netlist, KiCad conversion of 04192023_DAF0TMB3IC0_F0TG_MB_C_brd_V02_OCP.brd

Q7000  MOSFET_PCH_GDS_ESD_PROTECTED  DMP2035U-7 EMPTY  pkg SOT23_GDSXC  page 169
  D  = P12V_AUX_DSC_G2
  G  = P12V_AUX_DSC_G1
  S  = P12V_AUX_DSC_S1

PC6605  Q_CAP  1UF 16V 10% X6S  pkg C0402  page 362 : A = PV09_RETIMER_CPU0_VCCS ; B = GND

(kicad_pcb
	(version 20260206)
	(generator "pcbnew")
	(generator_version "10.0")
	(general
		(thickness 1.6)
		(legacy_teardrops no)
	)
	(paper "A4")
	(title_block
		(title "04192023_DAF0TMB3IC0_F0TG_MB_C_brd_V02_OCP.brd")
		(comment 1 "Grand Teton / footprints 3917-3918 of 8354")
	)
	(layers
		(0 "F.Cu" signal "TOP")
		(4 "In1.Cu" signal "GND")
		(6 "In2.Cu" signal "IN1")
		(8 "In3.Cu" signal "GND1")
		(10 "In4.Cu" signal "IN2")
		(12 "In5.Cu" signal "GND2")
		(14 "In6.Cu" signal "IN3")
		(16 "In7.Cu" signal "GND3")
		(18 "In8.Cu" signal "VCC")
		(20 "In9.Cu" signal "VCC1")
		(22 "In10.Cu" signal "GND4")
		(24 "In11.Cu" signal "IN4")
		(26 "In12.Cu" signal "GND5")
		(28 "In13.Cu" signal "IN5")
		(30 "In14.Cu" signal "GND6")
		(32 "In15.Cu" signal "IN6")
		(34 "In16.Cu" signal "GND7")
		(2 "B.Cu" signal "BOTTOM")
		(9 "F.Adhes" user "F.Adhesive")
		(11 "B.Adhes" user "B.Adhesive")
		(13 "F.Paste" user "Package Geometry/Pastemask Top")
		(15 "B.Paste" user "Package Geometry/Pastemask Bottom")
		(5 "F.SilkS" user "Ref Des/Silkscreen Top")
		(7 "B.SilkS" user "Ref Des/Silkscreen Bottom")
		(1 "F.Mask" user "Board Geometry/Soldermask Top")
		(3 "B.Mask" user "Board Geometry/Soldermask Bottom")
		(17 "Dwgs.User" user "User.Drawings")
		(19 "Cmts.User" user "User.Comments")
		(21 "Eco1.User" user "User.Eco1")
		(23 "Eco2.User" user "User.Eco2")
		(25 "Edge.Cuts" user "Board Geometry/Outline")
		(27 "Margin" user)
		(31 "F.CrtYd" user "Package Geometry/Place Bound Top")
		(29 "B.CrtYd" user "Package Geometry/Place Bound Bottom")
		(35 "F.Fab" user "Ref Des/Assembly Top")
		(33 "B.Fab" user "Ref Des/Assembly Bottom")
	)
	(footprint ""
		(layer "F.Cu")
		(at 447.919602 -428.61611 90)
		(property "Reference" "PC6605"
			(at 0 0 90)
			(layer "F.SilkS")
			(hide yes)
			(effects
				(font
					(size 1.27 1.27)
				)
			)
		)
		(property "Value" ""
			(at 0 0 90)
			(layer "F.Fab")
			(effects
				(font
					(size 1.27 1.27)
				)
			)
		)
		(duplicate_pad_numbers_are_jumpers no)
		(fp_line
			(start 0.7874 -0.4064)
			(end 0.7874 0.4064)
			(stroke
				(width 0.1524)
				(type default)
			)
			(layer "F.SilkS")
		)
		(fp_line
			(start -0.7874 -0.4064)
			(end 0.7874 -0.4064)
			(stroke
				(width 0.1524)
				(type default)
			)
			(layer "F.SilkS")
		)
		(fp_line
			(start 0.7874 0.4064)
			(end -0.7874 0.4064)
			(stroke
				(width 0.1524)
				(type default)
			)
			(layer "F.SilkS")
		)
		(fp_line
			(start -0.7874 0.4064)
			(end -0.7874 -0.4064)
			(stroke
				(width 0.1524)
				(type default)
			)
			(layer "F.SilkS")
		)
		(fp_line
			(start -0.12065 -0.305054)
			(end -0.12065 -0.2794)
			(stroke
				(width 0.1)
				(type default)
			)
			(layer "F.Fab")
		)
		(fp_line
			(start -0.67945 -0.305054)
			(end -0.12065 -0.305054)
			(stroke
				(width 0.1)
				(type default)
			)
			(layer "F.Fab")
		)
		(fp_line
			(start 0.67945 -0.3048)
			(end 0.67945 0.3048)
			(stroke
				(width 0.1)
				(type default)
			)
			(layer "F.Fab")
		)
		(fp_line
			(start 0.12065 -0.3048)
			(end 0.67945 -0.3048)
			(stroke
				(width 0.1)
				(type default)
			)
			(layer "F.Fab")
		)
		(fp_line
			(start 0.12065 -0.2794)
			(end 0.12065 -0.3048)
			(stroke
				(width 0.1)
				(type default)
			)
			(layer "F.Fab")
		)
		(fp_line
			(start -0.12065 -0.2794)
			(end 0.12065 -0.2794)
			(stroke
				(width 0.1)
				(type default)
			)
			(layer "F.Fab")
		)
		(fp_line
			(start 0.120396 0.2794)
			(end -0.12065 0.2794)
			(stroke
				(width 0.1)
				(type default)
			)
			(layer "F.Fab")
		)
		(fp_line
			(start -0.12065 0.2794)
			(end -0.12065 0.3048)
			(stroke
				(width 0.1)
				(type default)
			)
			(layer "F.Fab")
		)
		(fp_line
			(start 0.67945 0.3048)
			(end 0.120396 0.3048)
			(stroke
				(width 0.1)
				(type default)
			)
			(layer "F.Fab")
		)
		(fp_line
			(start 0.120396 0.3048)
			(end 0.120396 0.2794)
			(stroke
				(width 0.1)
				(type default)
			)
			(layer "F.Fab")
		)
		(fp_line
			(start -0.12065 0.3048)
			(end -0.67945 0.3048)
			(stroke
				(width 0.1)
				(type default)
			)
			(layer "F.Fab")
		)
		(fp_line
			(start -0.67945 0.3048)
			(end -0.67945 -0.305054)
			(stroke
				(width 0.1)
				(type default)
			)
			(layer "F.Fab")
		)
		(pad "1" smd circle
			(at -0.40005 0 90)
			(size 0 0)
			(layers "F.Cu" "F.Mask" "F.Paste")
			(net "PV09_RETIMER_CPU0_VCCS")
		)
		(pad "2" smd circle
			(at 0.40005 0 90)
			(size 0 0)
			(layers "F.Cu" "F.Mask" "F.Paste")
			(net "GND")
		)
	)
	(footprint ""
		(layer "F.Cu")
		(at 39.27856 -108.72216 90)
		(property "Reference" "Q7000"
			(at -1.78816 2.61493 90)
			(unlocked yes)
			(layer "F.SilkS")
			(effects
				(font
					(size 0.7874 0.5842)
					(thickness 0.1524)
				)
				(justify left)
			)
		)
		(property "Value" ""
			(at 0 0 90)
			(layer "F.Fab")
			(effects
				(font
					(size 1.27 1.27)
				)
			)
		)
		(duplicate_pad_numbers_are_jumpers no)
		(fp_line
			(start 1.603248 -1.500124)
			(end 1.603248 1.500124)
			(stroke
				(width 0.1524)
				(type default)
			)
			(layer "F.SilkS")
		)
		(fp_line
			(start -1.603248 -1.500124)
			(end 1.603248 -1.500124)
			(stroke
				(width 0.1524)
				(type default)
			)
			(layer "F.SilkS")
		)
		(fp_line
			(start 1.603248 1.500124)
			(end -1.603248 1.500124)
			(stroke
				(width 0.1524)
				(type default)
			)
			(layer "F.SilkS")
		)
		(fp_line
			(start -1.603248 1.500124)
			(end -1.603248 -1.500124)
			(stroke
				(width 0.1524)
				(type default)
			)
			(layer "F.SilkS")
		)
		(fp_line
			(start 0.700024 -1.500124)
			(end -0.700024 -1.500124)
			(stroke
				(width 0.1)
				(type default)
			)
			(layer "F.Fab")
		)
		(fp_line
			(start -0.700024 -1.500124)
			(end -0.700024 -1.169924)
			(stroke
				(width 0.1)
				(type default)
			)
			(layer "F.Fab")
		)
		(fp_line
			(start -0.700024 -1.169924)
			(end -1.249934 -1.169924)
			(stroke
				(width 0.1)
				(type default)
			)
			(layer "F.Fab")
		)
		(fp_line
			(start -1.249934 -1.169924)
			(end -1.249934 -0.729996)
			(stroke
				(width 0.1)
				(type default)
			)
			(layer "F.Fab")
		)
		(fp_line
			(start -0.6985 -0.729996)
			(end -0.6985 0.729996)
			(stroke
				(width 0.1)
				(type default)
			)
			(layer "F.Fab")
		)
		(fp_line
			(start -1.249934 -0.729996)
			(end -0.6985 -0.729996)
			(stroke
				(width 0.1)
				(type default)
			)
			(layer "F.Fab")
		)
		(fp_line
			(start 1.249934 -0.219964)
			(end 0.700024 -0.219964)
			(stroke
				(width 0.1)
				(type default)
			)
			(layer "F.Fab")
		)
		(fp_line
			(start 0.700024 -0.219964)
			(end 0.700024 -1.500124)
			(stroke
				(width 0.1)
				(type default)
			)
			(layer "F.Fab")
		)
		(fp_line
			(start 1.249934 0.219964)
			(end 1.249934 -0.219964)
			(stroke
				(width 0.1)
				(type default)
			)
			(layer "F.Fab")
		)
		(fp_line
			(start 0.700024 0.219964)
			(end 1.249934 0.219964)
			(stroke
				(width 0.1)
				(type default)
			)
			(layer "F.Fab")
		)
		(fp_line
			(start -0.6985 0.729996)
			(end -1.249934 0.729996)
			(stroke
				(width 0.1)
				(type default)
			)
			(layer "F.Fab")
		)
		(fp_line
			(start -1.249934 0.729996)
			(end -1.249934 1.169924)
			(stroke
				(width 0.1)
				(type default)
			)
			(layer "F.Fab")
		)
		(fp_line
			(start -0.700024 1.169924)
			(end -0.700024 1.500124)
			(stroke
				(width 0.1)
				(type default)
			)
			(layer "F.Fab")
		)
		(fp_line
			(start -1.249934 1.169924)
			(end -0.700024 1.169924)
			(stroke
				(width 0.1)
				(type default)
			)
			(layer "F.Fab")
		)
		(fp_line
			(start 0.700024 1.500124)
			(end 0.700024 0.219964)
			(stroke
				(width 0.1)
				(type default)
			)
			(layer "F.Fab")
		)
		(fp_line
			(start -0.700024 1.500124)
			(end 0.700024 1.500124)
			(stroke
				(width 0.1)
				(type default)
			)
			(layer "F.Fab")
		)
		(fp_rect
			(start -0.700024 1.500124)
			(end 0.700024 -1.500124)
			(stroke
				(width 0)
				(type default)
			)
			(fill no)
			(layer "F.Fab")
		)
		(pad "D" smd rect
			(at 0.999998 0)
			(size 0.8128 0.9144)
			(layers "F.Cu" "F.Mask" "F.Paste")
			(net "P12V_AUX_DSC_G2")
		)
		(pad "G" smd rect
			(at -0.999998 -0.94996)
			(size 0.8128 0.9144)
			(layers "F.Cu" "F.Mask" "F.Paste")
			(net "P12V_AUX_DSC_G1")
		)
		(pad "S" smd rect
			(at -0.999998 0.94996)
			(size 0.8128 0.9144)
			(layers "F.Cu" "F.Mask" "F.Paste")
			(net "P12V_AUX_DSC_S1")
		)
	)
)
